(kicad_pcb
	(version 20260206)
	(generator "pcbnew")
	(generator_version "10.0")
	(general
		(thickness 1.6)
		(legacy_teardrops no)
	)
	(paper "A4")
	(title_block
		(title "timecard-production-celestica-r4006 — R4006-B0001-02_R01.brd")
		(comment 1 "Time Appliance Project (Time Card) / footprints 590-592 of 1113")
	)
	(layers
		(0 "F.Cu" signal "TOP")
		(4 "In1.Cu" signal "L02_GND1")
		(6 "In2.Cu" signal "L03_SIG1")
		(8 "In3.Cu" signal "L04_GND2")
		(10 "In4.Cu" signal "L05_VCC1")
		(12 "In5.Cu" signal "L06_VCC2")
		(14 "In6.Cu" signal "L07_GND3")
		(16 "In7.Cu" signal "L08_SIG2")
		(18 "In8.Cu" signal "L09_GND4")
		(2 "B.Cu" signal "BOTTOM")
		(9 "F.Adhes" user "F.Adhesive")
		(11 "B.Adhes" user "B.Adhesive")
		(13 "F.Paste" user "Package Geometry/Pastemask Top")
		(15 "B.Paste" user "Package Geometry/Pastemask Bottom")
		(5 "F.SilkS" user "Ref Des/Silkscreen Top")
		(7 "B.SilkS" user "Ref Des/Silkscreen Bottom")
		(1 "F.Mask" user "Board Geometry/Soldermask Top")
		(3 "B.Mask" user "Board Geometry/Soldermask Bottom")
		(17 "Dwgs.User" user "User.Drawings")
		(19 "Cmts.User" user "User.Comments")
		(21 "Eco1.User" user "User.Eco1")
		(23 "Eco2.User" user "User.Eco2")
		(25 "Edge.Cuts" user "Board Geometry/Outline")
		(27 "Margin" user)
		(31 "F.CrtYd" user "Package Geometry/Place Bound Top")
		(29 "B.CrtYd" user "Package Geometry/Place Bound Bottom")
		(35 "F.Fab" user "Ref Des/Assembly Top")
		(33 "B.Fab" user "Ref Des/Assembly Bottom")
	)
	(footprint ""
		(layer "F.Cu")
		(at 105.2576 -101.3968 180)
		(property "Reference" "U33"
			(at -1.5494 5.11683 0)
			(unlocked yes)
			(layer "F.SilkS")
			(effects
				(font
					(size 0.7874 0.5842)
					(thickness 0.1524)
				)
			)
		)
		(property "Value" ""
			(at 0 0 180)
			(layer "F.Fab")
			(effects
				(font
					(size 1.27 1.27)
				)
			)
		)
		(property "Device Type" "IS32FL3207_QWLA3_TR_QFN29-A223A"
			(at 0 5.031486 180)
			(unlocked yes)
			(layer "F.Fab")
			(hide yes)
			(effects
				(font
					(size 0.7874 0.5842)
					(thickness 0.1524)
				)
			)
		)
		(property "User Part Number" "PARTNUM*"
			(at 0 6.225286 180)
			(unlocked yes)
			(layer "Cmts.User")
			(hide yes)
			(effects
				(font
					(size 0.7874 0.5842)
					(thickness 0.1524)
				)
			)
		)
		(duplicate_pad_numbers_are_jumpers no)
		(fp_line
			(start 3.29184 3.29184)
			(end 3.29184 -3.29184)
			(stroke
				(width 0.1)
				(type default)
			)
			(layer "F.SilkS")
		)
		(fp_line
			(start 3.29184 -3.29184)
			(end -3.29184 -3.29184)
			(stroke
				(width 0.1)
				(type default)
			)
			(layer "F.SilkS")
		)
		(fp_line
			(start -3.29184 3.29184)
			(end 3.29184 3.29184)
			(stroke
				(width 0.1)
				(type default)
			)
			(layer "F.SilkS")
		)
		(fp_line
			(start -3.29184 -3.29184)
			(end -3.29184 3.29184)
			(stroke
				(width 0.1)
				(type default)
			)
			(layer "F.SilkS")
		)
		(fp_poly
			(pts
				(arc
					(start -4.659122 -1.500124)
					(mid -3.643122 -1.500124)
					(end -4.659122 -1.500124)
				)
			)
			(stroke
				(width 0)
				(type default)
			)
			(fill yes)
			(layer "F.SilkS")
		)
		(fp_poly
			(pts
				(xy 1.4605 0.4191)
				(arc
					(start 0.753618 0.4191)
					(mid 0.700385 0.341015)
					(end 0.6223 0.287782)
				)
				(xy 0.6223 -0.4191) (xy 1.4605 -0.4191)
			)
			(stroke
				(width 0)
				(type default)
			)
			(fill yes)
			(layer "F.Paste")
		)
		(fp_poly
			(pts
				(xy 0.4191 1.4605) (xy -0.4191 1.4605)
				(arc
					(start -0.4191 0.753618)
					(mid -0.341015 0.700385)
					(end -0.287782 0.6223)
				)
				(arc
					(start 0.287782 0.6223)
					(mid 0.341015 0.700385)
					(end 0.4191 0.753618)
				)
			)
			(stroke
				(width 0)
				(type default)
			)
			(fill yes)
			(layer "F.Paste")
		)
		(fp_poly
			(pts
				(arc
					(start 0.4191 -0.753618)
					(mid 0.341015 -0.700385)
					(end 0.287782 -0.6223)
				)
				(arc
					(start -0.287782 -0.6223)
					(mid -0.341015 -0.700385)
					(end -0.4191 -0.753618)
				)
				(xy -0.4191 -1.4605) (xy 0.4191 -1.4605)
			)
			(stroke
				(width 0)
				(type default)
			)
			(fill yes)
			(layer "F.Paste")
		)
		(fp_poly
			(pts
				(arc
					(start -0.6223 0.287782)
					(mid -0.700385 0.341015)
					(end -0.753618 0.4191)
				)
				(xy -1.4605 0.4191) (xy -1.4605 -0.4191)
				(arc
					(start -0.753618 -0.4191)
					(mid -0.700385 -0.341015)
					(end -0.6223 -0.287782)
				)
			)
			(stroke
				(width 0)
				(type default)
			)
			(fill yes)
			(layer "F.Paste")
		)
		(fp_poly
			(pts
				(arc
					(start 0.4191 0.287782)
					(mid 0.341015 0.341015)
					(end 0.287782 0.4191)
				)
				(arc
					(start -0.287782 0.4191)
					(mid -0.341015 0.341015)
					(end -0.4191 0.287782)
				)
				(arc
					(start -0.4191 -0.287782)
					(mid -0.341015 -0.341015)
					(end -0.287782 -0.4191)
				)
				(arc
					(start 0.287782 -0.4191)
					(mid 0.341015 -0.341015)
					(end 0.4191 -0.287782)
				)
			)
			(stroke
				(width 0)
				(type default)
			)
			(fill yes)
			(layer "F.Paste")
		)
		(fp_poly
			(pts
				(arc
					(start -0.6223 -0.753618)
					(mid -0.700385 -0.700385)
					(end -0.753618 -0.6223)
				)
				(xy -1.4605 -0.6223)
				(arc
					(start -1.4605 -1.20396)
					(mid -1.385214 -1.02599)
					(end -1.2065 -0.9525)
				)
				(arc
					(start -1.2065 -0.9525)
					(mid -1.026895 -1.026895)
					(end -0.9525 -1.2065)
				)
				(arc
					(start -0.9525 -1.2065)
					(mid -1.025108 -1.3843)
					(end -1.20142 -1.4605)
				)
				(xy -0.6223 -1.4605)
			)
			(stroke
				(width 0)
				(type default)
			)
			(fill yes)
			(layer "F.Paste")
		)
		(fp_poly
			(pts
				(xy 1.4605 -0.6223)
				(arc
					(start 0.753618 -0.6223)
					(mid 0.700385 -0.700385)
					(end 0.6223 -0.753618)
				)
				(xy 0.6223 -1.4605)
				(arc
					(start 1.20142 -1.4605)
					(mid 1.025072 -1.384336)
					(end 0.9525 -1.2065)
				)
				(arc
					(start 0.9525 -1.2065)
					(mid 1.026895 -1.026895)
					(end 1.2065 -0.9525)
				)
				(arc
					(start 1.2065 -0.9525)
					(mid 1.380633 -1.021584)
					(end 1.459992 -1.19126)
				)
				(xy 1.4605 -1.19126)
			)
			(stroke
				(width 0)
				(type default)
			)
			(fill yes)
			(layer "F.Paste")
		)
		(fp_poly
			(pts
				(arc
					(start 0.9525 1.2065)
					(mid 1.025999 1.385205)
					(end 1.20396 1.4605)
				)
				(xy 0.6223 1.4605)
				(arc
					(start 0.6223 0.753618)
					(mid 0.700385 0.700385)
					(end 0.753618 0.6223)
				)
				(xy 1.4605 0.6223) (xy 1.4605 1.1938)
				(arc
					(start 1.460246 1.1938)
					(mid 1.381602 1.022415)
					(end 1.2065 0.9525)
				)
				(arc
					(start 1.2065 0.9525)
					(mid 1.026895 1.026895)
					(end 0.9525 1.2065)
				)
			)
			(stroke
				(width 0)
				(type default)
			)
			(fill yes)
			(layer "F.Paste")
		)
		(fp_poly
			(pts
				(xy -0.6223 1.4605) (xy -1.19634 1.4605)
				(arc
					(start -1.196594 1.460246)
					(mid -1.023469 1.382525)
					(end -0.9525 1.2065)
				)
				(arc
					(start -0.9525 1.2065)
					(mid -1.026895 1.026895)
					(end -1.2065 0.9525)
				)
				(arc
					(start -1.2065 0.9525)
					(mid -1.3843 1.025108)
					(end -1.4605 1.20142)
				)
				(xy -1.4605 0.6223)
				(arc
					(start -0.753618 0.6223)
					(mid -0.700385 0.700385)
					(end -0.6223 0.753618)
				)
			)
			(stroke
				(width 0)
				(type default)
			)
			(fill yes)
			(layer "F.Paste")
		)
		(fp_rect
			(start -3.54584 3.54584)
			(end 3.54584 -3.54584)
			(stroke
				(width 0)
				(type default)
			)
			(fill no)
			(layer "F.CrtYd")
		)
		(fp_line
			(start 2.500122 2.500122)
			(end 2.500122 -2.500122)
			(stroke
				(width 0.1)
				(type default)
			)
			(layer "F.Fab")
		)
		(fp_line
			(start 2.500122 -2.500122)
			(end -2.500122 -2.500122)
			(stroke
				(width 0.1)
				(type default)
			)
			(layer "F.Fab")
		)
		(fp_line
			(start -2.500122 2.500122)
			(end 2.500122 2.500122)
			(stroke
				(width 0.1)
				(type default)
			)
			(layer "F.Fab")
		)
		(fp_line
			(start -2.500122 -2.500122)
			(end -2.500122 2.500122)
			(stroke
				(width 0.1)
				(type default)
			)
			(layer "F.Fab")
		)
		(fp_poly
			(pts
				(arc
					(start -4.216654 -1.5748)
					(mid -3.200654 -1.5748)
					(end -4.216654 -1.5748)
				)
			)
			(stroke
				(width 0)
				(type default)
			)
			(fill yes)
			(layer "F.Fab")
		)
		(fp_text user "15"
			(at 4.1656 1.44145 0)
			(unlocked yes)
			(layer "F.SilkS")
			(effects
				(font
					(size 0.635 0.4064)
					(thickness 0.1524)
				)
			)
		)
		(fp_text user "21"
			(at 4.0386 -1.35255 0)
			(unlocked yes)
			(layer "F.SilkS")
			(effects
				(font
					(size 0.635 0.4064)
					(thickness 0.1524)
				)
			)
		)
		(fp_text user "14"
			(at 2.0066 4.10845 0)
			(unlocked yes)
			(layer "F.SilkS")
			(effects
				(font
					(size 0.635 0.4064)
					(thickness 0.1524)
				)
			)
		)
		(fp_text user "22"
			(at 1.6256 -3.76555 0)
			(unlocked yes)
			(layer "F.SilkS")
			(effects
				(font
					(size 0.635 0.4064)
					(thickness 0.1524)
				)
			)
		)
		(fp_text user "8"
			(at -1.5494 3.98145 0)
			(unlocked yes)
			(layer "F.SilkS")
			(effects
				(font
					(size 0.635 0.4064)
					(thickness 0.1524)
				)
			)
		)
		(fp_text user "28"
			(at -2.0574 -3.89255 0)
			(unlocked yes)
			(layer "F.SilkS")
			(effects
				(font
					(size 0.635 0.4064)
					(thickness 0.1524)
				)
			)
		)
		(fp_text user "7"
			(at -3.8354 2.12725 0)
			(unlocked yes)
			(layer "F.SilkS")
			(effects
				(font
					(size 0.635 0.4064)
					(thickness 0.1524)
				)
			)
		)
		(fp_text user "15"
			(at 4.20624 1.710182 0)
			(unlocked yes)
			(layer "F.Fab")
			(effects
				(font
					(size 0.7874 0.5842)
					(thickness 0.1524)
				)
			)
		)
		(fp_text user "21"
			(at 4.20624 -1.290066 0)
			(unlocked yes)
			(layer "F.Fab")
			(effects
				(font
					(size 0.7874 0.5842)
					(thickness 0.1524)
				)
			)
		)
		(fp_text user "14"
			(at 1.500124 4.239006 0)
			(unlocked yes)
			(layer "F.Fab")
			(effects
				(font
					(size 0.7874 0.5842)
					(thickness 0.1524)
				)
			)
		)
		(fp_text user "22"
			(at 1.500124 -3.792982 0)
			(unlocked yes)
			(layer "F.Fab")
			(effects
				(font
					(size 0.7874 0.5842)
					(thickness 0.1524)
				)
			)
		)
		(fp_text user "8"
			(at -1.500124 4.239006 0)
			(unlocked yes)
			(layer "F.Fab")
			(effects
				(font
					(size 0.7874 0.5842)
					(thickness 0.1524)
				)
			)
		)
		(fp_text user "28"
			(at -1.500124 -3.792982 0)
			(unlocked yes)
			(layer "F.Fab")
			(effects
				(font
					(size 0.7874 0.5842)
					(thickness 0.1524)
				)
			)
		)
		(fp_text user "7"
			(at -4.20624 1.710182 0)
			(unlocked yes)
			(layer "F.Fab")
			(effects
				(font
					(size 0.7874 0.5842)
					(thickness 0.1524)
				)
			)
		)
		(pad "1" smd rect
			(at -2.45364 -1.500124 180)
			(size 1.1684 0.3048)
			(layers "F.Cu" "F.Mask" "F.Paste")
			(net "RGB_LED_SHUTDOWN_N")
		)
		(pad "2" smd rect
			(at -2.41554 -0.999998 180)
			(size 1.2446 0.3048)
			(layers "F.Cu" "F.Mask" "F.Paste")
			(net "UNNAMED_14_IS32FL3207QWLA3TRQFN")
		)
		(pad "3" smd rect
			(at -2.41554 -0.500126 180)
			(size 1.2446 0.3048)
			(layers "F.Cu" "F.Mask" "F.Paste")
			(net "XP3R3V_FPGA")
		)
		(pad "4" smd rect
			(at -2.41554 0 180)
			(size 1.2446 0.3048)
			(layers "F.Cu" "F.Mask" "F.Paste")
			(net "SG")
		)
		(pad "5" smd rect
			(at -2.41554 0.500126 180)
			(size 1.2446 0.3048)
			(layers "F.Cu" "F.Mask" "F.Paste")
			(net "UNNAMED_14_IS32FL3207QWLA3TRQ_1")
		)
		(pad "6" smd rect
			(at -2.41554 0.999998 180)
			(size 1.2446 0.3048)
			(layers "F.Cu" "F.Mask" "F.Paste")
			(net "R_RGB_LED_I2C_SDA")
		)
		(pad "7" smd rect
			(at -2.45364 1.500124 180)
			(size 1.1684 0.3048)
			(layers "F.Cu" "F.Mask" "F.Paste")
			(net "R_RGB_LED_I2C_SCL")
		)
		(pad "8" smd rect
			(at -1.500124 2.45364 180)
			(size 0.3048 1.1684)
			(layers "F.Cu" "F.Mask" "F.Paste")
			(net "SMA1_LED_GREEN_N")
		)
		(pad "9" smd rect
			(at -0.999998 2.41554 180)
			(size 0.3048 1.2446)
			(layers "F.Cu" "F.Mask" "F.Paste")
			(net "SMA1_LED_RED_N")
		)
		(pad "10" smd rect
			(at -0.500126 2.41554 180)
			(size 0.3048 1.2446)
			(layers "F.Cu" "F.Mask" "F.Paste")
			(net "SMA1_LED_BLUE_N")
		)
		(pad "11" smd rect
			(at 0 2.41554 180)
			(size 0.3048 1.2446)
			(layers "F.Cu" "F.Mask" "F.Paste")
			(net "SG")
		)
		(pad "12" smd rect
			(at 0.500126 2.41554 180)
			(size 0.3048 1.2446)
			(layers "F.Cu" "F.Mask" "F.Paste")
			(net "SMA2_LED_GREEN_N")
		)
		(pad "13" smd rect
			(at 0.999998 2.41554 180)
			(size 0.3048 1.2446)
			(layers "F.Cu" "F.Mask" "F.Paste")
			(net "SMA2_LED_RED_N")
		)
		(pad "14" smd rect
			(at 1.500124 2.45364 180)
			(size 0.3048 1.1684)
			(layers "F.Cu" "F.Mask" "F.Paste")
			(net "SMA2_LED_BLUE_N")
		)
		(pad "15" smd rect
			(at 2.45364 1.500124 180)
			(size 1.1684 0.3048)
			(layers "F.Cu" "F.Mask" "F.Paste")
			(net "SMA3_LED_GREEN_N")
		)
		(pad "16" smd rect
			(at 2.41554 0.999998 180)
			(size 1.2446 0.3048)
			(layers "F.Cu" "F.Mask" "F.Paste")
			(net "SMA3_LED_RED_N")
		)
		(pad "17" smd rect
			(at 2.41554 0.500126 180)
			(size 1.2446 0.3048)
			(layers "F.Cu" "F.Mask" "F.Paste")
			(net "SMA3_LED_BLUE_N")
		)
		(pad "18" smd rect
			(at 2.41554 0 180)
			(size 1.2446 0.3048)
			(layers "F.Cu" "F.Mask" "F.Paste")
			(net "SG")
		)
		(pad "19" smd rect
			(at 2.41554 -0.500126 180)
			(size 1.2446 0.3048)
			(layers "F.Cu" "F.Mask" "F.Paste")
			(net "SMA4_LED_GREEN_N")
		)
		(pad "20" smd rect
			(at 2.41554 -0.999998 180)
			(size 1.2446 0.3048)
			(layers "F.Cu" "F.Mask" "F.Paste")
			(net "SMA4_LED_RED_N")
		)
		(pad "21" smd rect
			(at 2.45364 -1.500124 180)
			(size 1.1684 0.3048)
			(layers "F.Cu" "F.Mask" "F.Paste")
			(net "SMA4_LED_BLUE_N")
		)
		(pad "22" smd rect
			(at 1.500124 -2.45364 180)
			(size 0.3048 1.1684)
			(layers "F.Cu" "F.Mask" "F.Paste")
			(net "GPS_SMA_LED_GREEN_N")
		)
		(pad "23" smd rect
			(at 0.999998 -2.41554 180)
			(size 0.3048 1.2446)
			(layers "F.Cu" "F.Mask" "F.Paste")
			(net "GPS_SMA_LED_RED_N")
		)
		(pad "24" smd rect
			(at 0.500126 -2.41554 180)
			(size 0.3048 1.2446)
			(layers "F.Cu" "F.Mask" "F.Paste")
			(net "GPS_SMA_LED_BLUE_N")
		)
		(pad "25" smd rect
			(at 0 -2.41554 180)
			(size 0.3048 1.2446)
			(layers "F.Cu" "F.Mask" "F.Paste")
			(net "SG")
		)
		(pad "26" smd rect
			(at -0.500126 -2.41554 180)
			(size 0.3048 1.2446)
			(layers "F.Cu" "F.Mask" "F.Paste")
			(net "Net_785")
		)
		(pad "27" smd rect
			(at -0.999998 -2.41554 180)
			(size 0.3048 1.2446)
			(layers "F.Cu" "F.Mask" "F.Paste")
			(net "Net_784")
		)
		(pad "28" smd rect
			(at -1.500124 -2.45364 180)
			(size 0.3048 1.1684)
			(layers "F.Cu" "F.Mask" "F.Paste")
			(net "Net_783")
		)
		(pad "29" smd rect
			(at 0 0 180)
			(size 2.921 2.921)
			(layers "F.Cu" "F.Mask" "F.Paste")
			(net "SG")
		)
	)
	(footprint ""
		(layer "F.Cu")
		(at 13.0556 -25.4)
		(property "Reference" "C311"
			(at -2.6416 0.03937 0)
			(unlocked yes)
			(layer "F.SilkS")
			(effects
				(font
					(size 0.7874 0.5842)
					(thickness 0.1524)
				)
			)
		)
		(property "Value" "VAL*"
			(at 0.193548 2.13614 0)
			(unlocked yes)
			(layer "F.Fab")
			(hide yes)
			(effects
				(font
					(size 0.7874 0.5842)
					(thickness 0.1524)
				)
			)
		)
		(property "User Part Number" "PARTNUM*"
			(at 0.216154 4.185666 0)
			(unlocked yes)
			(layer "Cmts.User")
			(hide yes)
			(effects
				(font
					(size 0.7874 0.5842)
					(thickness 0.1524)
				)
			)
		)
		(property "Device Type" "CAPACITOR-G104-0A180-FJ,18PF,5%"
			(at 0.184404 1.180592 0)
			(unlocked yes)
			(layer "F.Fab")
			(hide yes)
			(effects
				(font
					(size 0.7874 0.5842)
					(thickness 0.1524)
				)
			)
		)
		(property "Tolerance" "TOL*"
			(at 0.216154 3.1496 0)
			(unlocked yes)
			(layer "Cmts.User")
			(hide yes)
			(effects
				(font
					(size 0.7874 0.5842)
					(thickness 0.1524)
				)
			)
		)
		(duplicate_pad_numbers_are_jumpers no)
		(fp_line
			(start -0.671322 -0.4445)
			(end 0.671322 -0.4445)
			(stroke
				(width 0.1)
				(type default)
			)
			(layer "F.SilkS")
		)
		(fp_line
			(start -0.671322 0.4445)
			(end -0.671322 -0.4445)
			(stroke
				(width 0.1)
				(type default)
			)
			(layer "F.SilkS")
		)
		(fp_line
			(start 0.671322 -0.4445)
			(end 0.671322 0.4445)
			(stroke
				(width 0.1)
				(type default)
			)
			(layer "F.SilkS")
		)
		(fp_line
			(start 0.671322 0.4445)
			(end -0.671322 0.4445)
			(stroke
				(width 0.1)
				(type default)
			)
			(layer "F.SilkS")
		)
		(fp_rect
			(start -0.671322 0.4445)
			(end 0.671322 -0.4445)
			(stroke
				(width 0)
				(type default)
			)
			(fill no)
			(layer "F.CrtYd")
		)
		(fp_line
			(start -0.31496 -0.1651)
			(end -0.31496 0.1651)
			(stroke
				(width 0.1)
				(type default)
			)
			(layer "F.Fab")
		)
		(fp_line
			(start -0.31496 0.1651)
			(end 0.31496 0.1651)
			(stroke
				(width 0.1)
				(type default)
			)
			(layer "F.Fab")
		)
		(fp_line
			(start 0.31496 -0.1651)
			(end -0.31496 -0.1651)
			(stroke
				(width 0.1)
				(type default)
			)
			(layer "F.Fab")
		)
		(fp_line
			(start 0.31496 0.1651)
			(end 0.31496 -0.1651)
			(stroke
				(width 0.1)
				(type default)
			)
			(layer "F.Fab")
		)
		(pad "1" smd rect
			(at -0.264922 0)
			(size 0.3048 0.381)
			(layers "F.Cu" "F.Mask" "F.Paste")
			(net "SG")
		)
		(pad "2" smd rect
			(at 0.264922 0)
			(size 0.3048 0.381)
			(layers "F.Cu" "F.Mask" "F.Paste")
			(net "UNNAMED_12_CAPACITOR_I321_2")
		)
		(zone
			(layer "F.Cu")
			(hatch none 0.5)
			(connect_pads
				(clearance 0)
			)
			(min_thickness 0.25)
			(keepout
				(tracks allowed)
				(vias not_allowed)
				(pads allowed)
				(copperpour not_allowed)
				(footprints allowed)
			)
			(placement
				(enabled no)
				(sheetname "")
			)
			(fill
				(thermal_gap 0.5)
				(thermal_bridge_width 0.5)
				(island_removal_mode 0)
			)
			(polygon
				(pts
					(xy 12.943078 -25.5905) (xy 12.943078 -25.2095) (xy 13.168122 -25.2095) (xy 13.168122 -25.5905)
				)
			)
		)
		(zone
			(layer "F.Cu")
			(hatch none 0.5)
			(connect_pads
				(clearance 0)
			)
			(min_thickness 0.25)
			(keepout
				(tracks not_allowed)
				(vias allowed)
				(pads allowed)
				(copperpour not_allowed)
				(footprints allowed)
			)
			(placement
				(enabled no)
				(sheetname "")
			)
			(fill
				(thermal_gap 0.5)
				(thermal_bridge_width 0.5)
				(island_removal_mode 0)
			)
			(polygon
				(pts
					(xy 12.943078 -25.2095) (xy 13.168122 -25.2095) (xy 13.168122 -25.5905) (xy 12.943078 -25.5905)
				)
			)
		)
	)
	(footprint ""
		(layer "F.Cu")
		(at 36.83 -125.603)
		(property "Reference" "SP75"
			(at 0 0 0)
			(layer "F.SilkS")
			(hide yes)
			(effects
				(font
					(size 1.27 1.27)
				)
			)
		)
		(property "Value" ""
			(at 0 0 0)
			(layer "F.Fab")
			(effects
				(font
					(size 1.27 1.27)
				)
			)
		)
		(duplicate_pad_numbers_are_jumpers no)
	)
)
